# T6G (Grand Teton) — schematic netlist excerpt (pin names and nets, part order shuffled) for the footprints in the layout excerpt that follows; sources: Cadence DE-HDL packaged netlist, KiCad conversion of 04192023_DAF0TMB3IC0_F0TG_MB_C_brd_V02_OCP.brd

R854  Q_RES  0 5% CHIP  pkg 0201LF  page 342 : A = RST_RT_CPU1_P2_PERST_N ; B = RST_RT_CPU1_P2_PERST_R_N
R54  Q_RES  1K 1% CHIP  pkg 0402LF  page 238 : A = CPU_FRU_ADDR2 ; B = GND
R3281  Q_RES  1K 1% EMPTY  pkg 0402LF  page 111 : A = FM_P2E_EQB1 ; B = GND

(kicad_pcb
	(version 20260206)
	(generator "pcbnew")
	(generator_version "10.0")
	(general
		(thickness 1.6)
		(legacy_teardrops no)
	)
	(paper "A4")
	(title_block
		(title "04192023_DAF0TMB3IC0_F0TG_MB_C_brd_V02_OCP.brd")
		(comment 1 "Grand Teton / footprints 1677-1679 of 8354")
	)
	(layers
		(0 "F.Cu" signal "TOP")
		(4 "In1.Cu" signal "GND")
		(6 "In2.Cu" signal "IN1")
		(8 "In3.Cu" signal "GND1")
		(10 "In4.Cu" signal "IN2")
		(12 "In5.Cu" signal "GND2")
		(14 "In6.Cu" signal "IN3")
		(16 "In7.Cu" signal "GND3")
		(18 "In8.Cu" signal "VCC")
		(20 "In9.Cu" signal "VCC1")
		(22 "In10.Cu" signal "GND4")
		(24 "In11.Cu" signal "IN4")
		(26 "In12.Cu" signal "GND5")
		(28 "In13.Cu" signal "IN5")
		(30 "In14.Cu" signal "GND6")
		(32 "In15.Cu" signal "IN6")
		(34 "In16.Cu" signal "GND7")
		(2 "B.Cu" signal "BOTTOM")
		(9 "F.Adhes" user "F.Adhesive")
		(11 "B.Adhes" user "B.Adhesive")
		(13 "F.Paste" user "Package Geometry/Pastemask Top")
		(15 "B.Paste" user "Package Geometry/Pastemask Bottom")
		(5 "F.SilkS" user "Ref Des/Silkscreen Top")
		(7 "B.SilkS" user "Ref Des/Silkscreen Bottom")
		(1 "F.Mask" user "Board Geometry/Soldermask Top")
		(3 "B.Mask" user "Board Geometry/Soldermask Bottom")
		(17 "Dwgs.User" user "User.Drawings")
		(19 "Cmts.User" user "User.Comments")
		(21 "Eco1.User" user "User.Eco1")
		(23 "Eco2.User" user "User.Eco2")
		(25 "Edge.Cuts" user "Board Geometry/Outline")
		(27 "Margin" user)
		(31 "F.CrtYd" user "Package Geometry/Place Bound Top")
		(29 "B.CrtYd" user "Package Geometry/Place Bound Bottom")
		(35 "F.Fab" user "Ref Des/Assembly Top")
		(33 "B.Fab" user "Ref Des/Assembly Bottom")
	)
	(footprint ""
		(layer "F.Cu")
		(at 30.315662 -429.759364 90)
		(property "Reference" "R3281"
			(at 0 0 90)
			(layer "F.SilkS")
			(hide yes)
			(effects
				(font
					(size 1.27 1.27)
				)
			)
		)
		(property "Value" ""
			(at 0 0 90)
			(layer "F.Fab")
			(effects
				(font
					(size 1.27 1.27)
				)
			)
		)
		(duplicate_pad_numbers_are_jumpers no)
		(fp_line
			(start 0.7874 -0.4064)
			(end 0.7874 0.4064)
			(stroke
				(width 0.1524)
				(type default)
			)
			(layer "F.SilkS")
		)
		(fp_line
			(start -0.7874 -0.4064)
			(end 0.7874 -0.4064)
			(stroke
				(width 0.1524)
				(type default)
			)
			(layer "F.SilkS")
		)
		(fp_line
			(start 0.7874 0.4064)
			(end -0.7874 0.4064)
			(stroke
				(width 0.1524)
				(type default)
			)
			(layer "F.SilkS")
		)
		(fp_line
			(start -0.7874 0.4064)
			(end -0.7874 -0.4064)
			(stroke
				(width 0.1524)
				(type default)
			)
			(layer "F.SilkS")
		)
		(fp_line
			(start -0.12065 -0.305054)
			(end -0.12065 -0.2794)
			(stroke
				(width 0.1)
				(type default)
			)
			(layer "F.Fab")
		)
		(fp_line
			(start -0.67945 -0.305054)
			(end -0.12065 -0.305054)
			(stroke
				(width 0.1)
				(type default)
			)
			(layer "F.Fab")
		)
		(fp_line
			(start 0.67945 -0.3048)
			(end 0.67945 0.3048)
			(stroke
				(width 0.1)
				(type default)
			)
			(layer "F.Fab")
		)
		(fp_line
			(start 0.12065 -0.3048)
			(end 0.67945 -0.3048)
			(stroke
				(width 0.1)
				(type default)
			)
			(layer "F.Fab")
		)
		(fp_line
			(start 0.12065 -0.2794)
			(end 0.12065 -0.3048)
			(stroke
				(width 0.1)
				(type default)
			)
			(layer "F.Fab")
		)
		(fp_line
			(start -0.12065 -0.2794)
			(end 0.12065 -0.2794)
			(stroke
				(width 0.1)
				(type default)
			)
			(layer "F.Fab")
		)
		(fp_line
			(start 0.120396 0.2794)
			(end -0.12065 0.2794)
			(stroke
				(width 0.1)
				(type default)
			)
			(layer "F.Fab")
		)
		(fp_line
			(start -0.12065 0.2794)
			(end -0.12065 0.3048)
			(stroke
				(width 0.1)
				(type default)
			)
			(layer "F.Fab")
		)
		(fp_line
			(start 0.67945 0.3048)
			(end 0.120396 0.3048)
			(stroke
				(width 0.1)
				(type default)
			)
			(layer "F.Fab")
		)
		(fp_line
			(start 0.120396 0.3048)
			(end 0.120396 0.2794)
			(stroke
				(width 0.1)
				(type default)
			)
			(layer "F.Fab")
		)
		(fp_line
			(start -0.12065 0.3048)
			(end -0.67945 0.3048)
			(stroke
				(width 0.1)
				(type default)
			)
			(layer "F.Fab")
		)
		(fp_line
			(start -0.67945 0.3048)
			(end -0.67945 -0.305054)
			(stroke
				(width 0.1)
				(type default)
			)
			(layer "F.Fab")
		)
		(pad "1" smd circle
			(at -0.40005 0 90)
			(size 0 0)
			(layers "F.Cu" "F.Mask" "F.Paste")
			(net "FM_P2E_EQB1")
		)
		(pad "2" smd circle
			(at 0.40005 0 90)
			(size 0 0)
			(layers "F.Cu" "F.Mask" "F.Paste")
			(net "GND")
		)
	)
	(footprint ""
		(layer "F.Cu")
		(at 167.79621 -395.6304 -90)
		(property "Reference" "R854"
			(at 0 0 270)
			(layer "F.SilkS")
			(hide yes)
			(effects
				(font
					(size 1.27 1.27)
				)
			)
		)
		(property "Value" ""
			(at 0 0 270)
			(layer "F.Fab")
			(effects
				(font
					(size 1.27 1.27)
				)
			)
		)
		(duplicate_pad_numbers_are_jumpers no)
		(fp_line
			(start -0.32512 0.175006)
			(end -0.32512 -0.175006)
			(stroke
				(width 0.1)
				(type default)
			)
			(layer "F.Fab")
		)
		(fp_line
			(start 0.32512 0.175006)
			(end -0.32512 0.175006)
			(stroke
				(width 0.1)
				(type default)
			)
			(layer "F.Fab")
		)
		(fp_line
			(start -0.32512 -0.175006)
			(end 0.32512 -0.175006)
			(stroke
				(width 0.1)
				(type default)
			)
			(layer "F.Fab")
		)
		(fp_line
			(start 0.32512 -0.175006)
			(end 0.32512 0.175006)
			(stroke
				(width 0.1)
				(type default)
			)
			(layer "F.Fab")
		)
		(pad "1" smd rect
			(at -0.2667 0 270)
			(size 0.3048 0.381)
			(layers "F.Cu" "F.Mask" "F.Paste")
			(net "RST_RT_CPU1_P2_PERST_N")
		)
		(pad "2" smd rect
			(at 0.2667 0 90)
			(size 0.3048 0.381)
			(layers "F.Cu" "F.Mask" "F.Paste")
			(net "RST_RT_CPU1_P2_PERST_R_N")
		)
	)
	(footprint ""
		(layer "F.Cu")
		(at 302.241458 -109.779308 180)
		(property "Reference" "R54"
			(at 0 0 180)
			(layer "F.SilkS")
			(hide yes)
			(effects
				(font
					(size 1.27 1.27)
				)
			)
		)
		(property "Value" ""
			(at 0 0 180)
			(layer "F.Fab")
			(effects
				(font
					(size 1.27 1.27)
				)
			)
		)
		(duplicate_pad_numbers_are_jumpers no)
		(fp_line
			(start 0.7874 0.4064)
			(end -0.7874 0.4064)
			(stroke
				(width 0.1524)
				(type default)
			)
			(layer "F.SilkS")
		)
		(fp_line
			(start 0.7874 -0.4064)
			(end 0.7874 0.4064)
			(stroke
				(width 0.1524)
				(type default)
			)
			(layer "F.SilkS")
		)
		(fp_line
			(start -0.7874 0.4064)
			(end -0.7874 -0.4064)
			(stroke
				(width 0.1524)
				(type default)
			)
			(layer "F.SilkS")
		)
		(fp_line
			(start -0.7874 -0.4064)
			(end 0.7874 -0.4064)
			(stroke
				(width 0.1524)
				(type default)
			)
			(layer "F.SilkS")
		)
		(fp_line
			(start 0.67945 0.3048)
			(end 0.120396 0.3048)
			(stroke
				(width 0.1)
				(type default)
			)
			(layer "F.Fab")
		)
		(fp_line
			(start 0.67945 -0.3048)
			(end 0.67945 0.3048)
			(stroke
				(width 0.1)
				(type default)
			)
			(layer "F.Fab")
		)
		(fp_line
			(start 0.12065 -0.2794)
			(end 0.12065 -0.3048)
			(stroke
				(width 0.1)
				(type default)
			)
			(layer "F.Fab")
		)
		(fp_line
			(start 0.12065 -0.3048)
			(end 0.67945 -0.3048)
			(stroke
				(width 0.1)
				(type default)
			)
			(layer "F.Fab")
		)
		(fp_line
			(start 0.120396 0.3048)
			(end 0.120396 0.2794)
			(stroke
				(width 0.1)
				(type default)
			)
			(layer "F.Fab")
		)
		(fp_line
			(start 0.120396 0.2794)
			(end -0.12065 0.2794)
			(stroke
				(width 0.1)
				(type default)
			)
			(layer "F.Fab")
		)
		(fp_line
			(start -0.12065 0.3048)
			(end -0.67945 0.3048)
			(stroke
				(width 0.1)
				(type default)
			)
			(layer "F.Fab")
		)
		(fp_line
			(start -0.12065 0.2794)
			(end -0.12065 0.3048)
			(stroke
				(width 0.1)
				(type default)
			)
			(layer "F.Fab")
		)
		(fp_line
			(start -0.12065 -0.2794)
			(end 0.12065 -0.2794)
			(stroke
				(width 0.1)
				(type default)
			)
			(layer "F.Fab")
		)
		(fp_line
			(start -0.12065 -0.305054)
			(end -0.12065 -0.2794)
			(stroke
				(width 0.1)
				(type default)
			)
			(layer "F.Fab")
		)
		(fp_line
			(start -0.67945 0.3048)
			(end -0.67945 -0.305054)
			(stroke
				(width 0.1)
				(type default)
			)
			(layer "F.Fab")
		)
		(fp_line
			(start -0.67945 -0.305054)
			(end -0.12065 -0.305054)
			(stroke
				(width 0.1)
				(type default)
			)
			(layer "F.Fab")
		)
		(pad "1" smd circle
			(at -0.40005 0 180)
			(size 0 0)
			(layers "F.Cu" "F.Mask" "F.Paste")
			(net "CPU_FRU_ADDR2")
		)
		(pad "2" smd circle
			(at 0.40005 0 180)
			(size 0 0)
			(layers "F.Cu" "F.Mask" "F.Paste")
			(net "GND")
		)
	)
)
